FILE_TYPE = CONNECTIVITY;
{Allegro Design Entry HDL 17.2-2016 S081 (4005846) 1/11/2022}
"PAGE_NUMBER" = 39;
0"NC";
1"VCCIO5\g";
%"LCMXO3LF2100C5BG256C"
"6","(-4800,4375)","0","pure_quanta","I1";
;
PART_NUMBER"AJ021000T03"
VALUE"LCMXO3LF-2100C-5BG256C"
MATERIAL"IC"
PART_TYPE"SMLF"
CDS_LMAN_SYM_OUTLINE"-600,675,600,-675"
NEEDS_NO_SIZE"TRUE"
CDS_LIB"pure_quanta"
LOCATION"U25"
$SEC"6"
CDS_SEC"6";
"PL4B"
$PN"F1"0;
"PL4A"
$PN"F3"0;
"PL4D"
$PN"G4"0;
"PL4C"
$PN"G5"0;
"VCCIO5"
$PN"E4"1;
"PL5D"
$PN"H6"0;
"PL5C"
$PN"F5"0;
"PL5B"
$PN"G3"0;
"PL5A"
$PN"G2"0;
"PL3D"
$PN"G6"0;
"PL3C"
$PN"F4"0;
"PL3B||PCLKC5_0"
$PN"F2"0;
"PL3A||PCLKT5_0"
$PN"E1"0;
"PL2D"
$PN"D2"0;
"PL2C"
$PN"C1"0;
"PL2B||L_GPLLC_IN"
$PN"E3"0;
"PL2A||L_GPLLT_IN"
$PN"E2"0;
"PL1B||L_GPLLC_FB"
$PN"D1"0;
"PL1A||L_GPLLT_FB"
$PN"D3"0;
"PL1D"
$PN"C2"0;
"PL1C"
$PN"B1"0;
%"UNIVERSAL_POWER"
"1","(-3675,4000)","0","logical_power","I3";
;
HDL_POWER"VCCIO5"
CDS_LIB"logical_power";
"A"1;
END.
